(kicad_pcb
	(version 20241229)
	(generator "pcbnew")
	(generator_version "9.0")
	(general
		(thickness 1.294)
		(legacy_teardrops no)
	)
	(paper "A3")
	(title_block
		(title "Kintex 410T devboard")
		(date "2024-04-03")
		(rev "1.1.2")
		(comment 9 "footprints 632-637 of 975")
	)
	(layers
		(0 "F.Cu" mixed)
		(4 "In1.Cu" power)
		(6 "In2.Cu" power)
		(8 "In3.Cu" mixed)
		(10 "In4.Cu" power)
		(12 "In5.Cu" mixed)
		(14 "In6.Cu" power)
		(16 "In7.Cu" mixed)
		(18 "In8.Cu" power)
		(2 "B.Cu" mixed)
		(9 "F.Adhes" user "F.Adhesive")
		(11 "B.Adhes" user "B.Adhesive")
		(13 "F.Paste" user)
		(15 "B.Paste" user)
		(5 "F.SilkS" user "F.Silkscreen")
		(7 "B.SilkS" user "B.Silkscreen")
		(1 "F.Mask" user)
		(3 "B.Mask" user)
		(17 "Dwgs.User" user "User.Drawings")
		(19 "Cmts.User" user "User.Comments")
		(21 "Eco1.User" user "User.Eco1")
		(23 "Eco2.User" user "User.Eco2")
		(25 "Edge.Cuts" user)
		(27 "Margin" user)
		(31 "F.CrtYd" user "F.Courtyard")
		(29 "B.CrtYd" user "B.Courtyard")
		(35 "F.Fab" user)
		(33 "B.Fab" user)
	)
	(footprint "antmicro-footprints:R_0402_1005Metric"
		(layer "B.Cu")
		(at 220.699999 77.899999 90)
		(descr "Resistor SMD 0402")
		(tags "resistor SMD 0402")
		(property "Reference" "R115"
			(at 3.599999 0.375001 270)
			(layer "B.SilkS")
			(effects
				(font
					(size 0.7 0.7)
					(thickness 0.15)
				)
				(justify left bottom mirror)
			)
		)
		(property "Value" "R_100R_0402"
			(at 0 -1.4 270)
			(layer "B.Fab")
			(effects
				(font
					(size 0.7 0.7)
					(thickness 0.15)
				)
				(justify left bottom mirror)
			)
		)
		(property "Description" "SMD Chip Resistor, 100 ohm, ± 1%, 62.5 mW, 0402 [1005 Metric], Thick Film, General Purpose"
			(at 0 0 90)
			(layer "F.Fab")
			(hide yes)
			(effects
				(font
					(size 1.27 1.27)
					(thickness 0.15)
				)
			)
		)
		(property "Author" "Antmicro"
			(at 298.599998 -142.8 0)
			(layer "B.Fab")
			(hide yes)
			(effects
				(font
					(size 1 1)
					(thickness 0.15)
				)
				(justify mirror)
			)
		)
		(property "License" "Apache-2.0"
			(at 298.599998 -142.8 0)
			(layer "B.Fab")
			(hide yes)
			(effects
				(font
					(size 1 1)
					(thickness 0.15)
				)
				(justify mirror)
			)
		)
		(property "MPN" "CR0402-FX-1000GLF"
			(at 298.599998 -142.8 0)
			(layer "B.Fab")
			(hide yes)
			(effects
				(font
					(size 1 1)
					(thickness 0.15)
				)
				(justify mirror)
			)
		)
		(property "Manufacturer" "Bourns"
			(at 298.599998 -142.8 0)
			(layer "B.Fab")
			(hide yes)
			(effects
				(font
					(size 1 1)
					(thickness 0.15)
				)
				(justify mirror)
			)
		)
		(property "Tolerance" "1%"
			(at 298.599998 -142.8 0)
			(layer "B.Fab")
			(hide yes)
			(effects
				(font
					(size 1 1)
					(thickness 0.15)
				)
				(justify mirror)
			)
		)
		(property "Val" "100R"
			(at 298.599998 -142.8 0)
			(layer "B.Fab")
			(hide yes)
			(effects
				(font
					(size 1 1)
					(thickness 0.15)
				)
				(justify mirror)
			)
		)
		(sheetname "User GPIO + LED + button + DIP switch")
		(sheetfile "user-gpio.kicad_sch")
		(attr smd)
		(fp_rect
			(start -0.925 0.47)
			(end 0.925 -0.47)
			(stroke
				(width 0.05)
				(type default)
			)
			(fill no)
			(layer "B.CrtYd")
		)
		(fp_rect
			(start -0.5 0.25)
			(end 0.5 -0.25)
			(stroke
				(width 0.15)
				(type solid)
			)
			(fill no)
			(layer "B.Fab")
		)
		(pad "1" smd roundrect
			(at -0.48 0 90)
			(size 0.59 0.64)
			(layers "B.Cu" "B.Mask" "B.Paste")
			(roundrect_rratio 0.25)
			(net 802 "/User GPIO + LED + button + DIP switch/PMOD_A_10")
			(pintype "passive")
		)
		(pad "2" smd roundrect
			(at 0.48 0 90)
			(size 0.59 0.64)
			(layers "B.Cu" "B.Mask" "B.Paste")
			(roundrect_rratio 0.25)
			(net 439 "/FPGA Bank 12 & 13/PMOD_A.IO10")
			(pintype "passive")
		)
	)
	(footprint "antmicro-footprints:R_0402_1005Metric"
		(layer "B.Cu")
		(at 195.691252 97.85 180)
		(descr "Resistor SMD 0402")
		(tags "resistor SMD 0402")
		(property "Reference" "R213"
			(at 0.716252 -0.425 0)
			(layer "B.SilkS")
			(effects
				(font
					(size 0.7 0.7)
					(thickness 0.15)
				)
				(justify left bottom mirror)
			)
		)
		(property "Value" "R_2k2_0402"
			(at 0 -1.4 0)
			(layer "B.Fab")
			(effects
				(font
					(size 0.7 0.7)
					(thickness 0.15)
				)
				(justify left bottom mirror)
			)
		)
		(property "Description" "SMD Chip Resistor, 2.2 kohm, ± 1%, 62.5 mW, 0402 [1005 Metric], Thick Film, General Purpose"
			(at 0 0 180)
			(layer "F.Fab")
			(hide yes)
			(effects
				(font
					(size 1.27 1.27)
					(thickness 0.15)
				)
			)
		)
		(property "Author" "Antmicro"
			(at 391.382504 195.7 0)
			(layer "B.Fab")
			(hide yes)
			(effects
				(font
					(size 1 1)
					(thickness 0.15)
				)
				(justify mirror)
			)
		)
		(property "License" "Apache-2.0"
			(at 391.382504 195.7 0)
			(layer "B.Fab")
			(hide yes)
			(effects
				(font
					(size 1 1)
					(thickness 0.15)
				)
				(justify mirror)
			)
		)
		(property "MPN" "CR0402-FX-2201GLF"
			(at 391.382504 195.7 0)
			(layer "B.Fab")
			(hide yes)
			(effects
				(font
					(size 1 1)
					(thickness 0.15)
				)
				(justify mirror)
			)
		)
		(property "Manufacturer" "Bourns"
			(at 391.382504 195.7 0)
			(layer "B.Fab")
			(hide yes)
			(effects
				(font
					(size 1 1)
					(thickness 0.15)
				)
				(justify mirror)
			)
		)
		(property "Tolerance" "1%"
			(at 391.382504 195.7 0)
			(layer "B.Fab")
			(hide yes)
			(effects
				(font
					(size 1 1)
					(thickness 0.15)
				)
				(justify mirror)
			)
		)
		(property "Val" "2k2"
			(at 391.382504 195.7 0)
			(layer "B.Fab")
			(hide yes)
			(effects
				(font
					(size 1 1)
					(thickness 0.15)
				)
				(justify mirror)
			)
		)
		(sheetname "HDMI + Ethernet")
		(sheetfile "hdmi-ethernet.kicad_sch")
		(attr smd)
		(fp_rect
			(start -0.925 0.47)
			(end 0.925 -0.47)
			(stroke
				(width 0.05)
				(type default)
			)
			(fill no)
			(layer "B.CrtYd")
		)
		(fp_rect
			(start -0.5 0.25)
			(end 0.5 -0.25)
			(stroke
				(width 0.15)
				(type solid)
			)
			(fill no)
			(layer "B.Fab")
		)
		(pad "1" smd roundrect
			(at -0.48 0 180)
			(size 0.59 0.64)
			(layers "B.Cu" "B.Mask" "B.Paste")
			(roundrect_rratio 0.25)
			(net 507 "/FPGA Bank 16 & 17/GBE_RGMII.GTR_CLK")
			(pintype "passive")
		)
		(pad "2" smd roundrect
			(at 0.48 0 180)
			(size 0.59 0.64)
			(layers "B.Cu" "B.Mask" "B.Paste")
			(roundrect_rratio 0.25)
			(net 1 "GND")
			(pintype "passive")
		)
	)
	(footprint "antmicro-footprints:R_Array_4x0201_Panasonic_EXB18V"
		(layer "B.Cu")
		(at 251.251 133.3 90)
		(property "Reference" "R63"
			(at -1.1 -0.701 270)
			(layer "B.SilkS")
			(effects
				(font
					(size 0.7 0.7)
					(thickness 0.15)
				)
				(justify right bottom mirror)
			)
		)
		(property "Value" "R_4x33R_0201_array"
			(at -1.1 -1.8 270)
			(layer "B.Fab")
			(effects
				(font
					(size 0.7 0.7)
					(thickness 0.15)
				)
				(justify left bottom mirror)
			)
		)
		(property "Description" "Fixed Network Resistor, 33 ohm, Isolated, 4 Resistors, 0502 [1406 Metric], Flat, ± 5%"
			(at 0 0 90)
			(layer "F.Fab")
			(hide yes)
			(effects
				(font
					(size 1.27 1.27)
					(thickness 0.15)
				)
			)
		)
		(property "Author" "Antmicro"
			(at 384.551 -117.951 0)
			(layer "B.Fab")
			(hide yes)
			(effects
				(font
					(size 1 1)
					(thickness 0.15)
				)
				(justify mirror)
			)
		)
		(property "License" "Apache-2.0"
			(at 384.551 -117.951 0)
			(layer "B.Fab")
			(hide yes)
			(effects
				(font
					(size 1 1)
					(thickness 0.15)
				)
				(justify mirror)
			)
		)
		(property "MPN" "EXB-18V330JX"
			(at 384.551 -117.951 0)
			(layer "B.Fab")
			(hide yes)
			(effects
				(font
					(size 1 1)
					(thickness 0.15)
				)
				(justify mirror)
			)
		)
		(property "Manufacturer" "Panasonic"
			(at 384.551 -117.951 0)
			(layer "B.Fab")
			(hide yes)
			(effects
				(font
					(size 1 1)
					(thickness 0.15)
				)
				(justify mirror)
			)
		)
		(property "Val" "R_4x33R_0201"
			(at 384.551 -117.951 0)
			(layer "B.Fab")
			(hide yes)
			(effects
				(font
					(size 1 1)
					(thickness 0.15)
				)
				(justify mirror)
			)
		)
		(sheetname "SPI Flash + SD Card")
		(sheetfile "spi-flash.kicad_sch")
		(attr smd)
		(fp_line
			(start 0.8 0.45)
			(end 0.8 -0.45)
			(stroke
				(width 0.12)
				(type solid)
			)
			(layer "B.SilkS")
		)
		(fp_line
			(start -0.8 0.45)
			(end -0.8 -0.45)
			(stroke
				(width 0.12)
				(type solid)
			)
			(layer "B.SilkS")
		)
		(fp_rect
			(start -0.898 0.66)
			(end 0.898 -0.65)
			(stroke
				(width 0.05)
				(type solid)
			)
			(fill no)
			(layer "B.CrtYd")
		)
		(pad "1" smd roundrect
			(at -0.6 -0.298 90)
			(size 0.2 0.4)
			(layers "B.Cu" "B.Mask" "B.Paste")
			(roundrect_rratio 0.25)
			(net 394 "/FPGA Bank 33 & 34/SD_CARD.CLK")
			(pinfunction "R1.1")
			(pintype "passive")
		)
		(pad "2" smd roundrect
			(at -0.202 -0.298 90)
			(size 0.2 0.4)
			(layers "B.Cu" "B.Mask" "B.Paste")
			(roundrect_rratio 0.25)
			(net 366 "unconnected-(R63-R2.1-Pad2)")
			(pinfunction "R2.1")
			(pintype "passive+no_connect")
		)
		(pad "3" smd roundrect
			(at 0.2 -0.298 90)
			(size 0.2 0.4)
			(layers "B.Cu" "B.Mask" "B.Paste")
			(roundrect_rratio 0.25)
			(net 395 "/FPGA Bank 33 & 34/SD_CARD.DAT0")
			(pinfunction "R3.1")
			(pintype "passive")
		)
		(pad "4" smd roundrect
			(at 0.598 -0.298 90)
			(size 0.2 0.4)
			(layers "B.Cu" "B.Mask" "B.Paste")
			(roundrect_rratio 0.25)
			(net 397 "/FPGA Bank 33 & 34/SD_CARD.DAT1")
			(pinfunction "R4.1")
			(pintype "passive")
		)
		(pad "5" smd roundrect
			(at 0.598 0.3 90)
			(size 0.2 0.4)
			(layers "B.Cu" "B.Mask" "B.Paste")
			(roundrect_rratio 0.25)
			(net 332 "Net-(J23-DAT1)")
			(pinfunction "R4.2")
			(pintype "passive")
		)
		(pad "6" smd roundrect
			(at 0.2 0.3 90)
			(size 0.2 0.4)
			(layers "B.Cu" "B.Mask" "B.Paste")
			(roundrect_rratio 0.25)
			(net 331 "Net-(J23-DAT0)")
			(pinfunction "R3.2")
			(pintype "passive")
		)
		(pad "7" smd roundrect
			(at -0.202 0.3 90)
			(size 0.2 0.4)
			(layers "B.Cu" "B.Mask" "B.Paste")
			(roundrect_rratio 0.25)
			(net 367 "unconnected-(R63-R2.2-Pad7)")
			(pinfunction "R2.2")
			(pintype "passive+no_connect")
		)
		(pad "8" smd roundrect
			(at -0.6 0.3 90)
			(size 0.2 0.4)
			(layers "B.Cu" "B.Mask" "B.Paste")
			(roundrect_rratio 0.25)
			(net 330 "Net-(J23-CLK)")
			(pinfunction "R1.2")
			(pintype "passive")
		)
	)
	(footprint "antmicro-footprints:R_0402_1005Metric"
		(layer "B.Cu")
		(at 225.626 148.201)
		(descr "Resistor SMD 0402")
		(tags "resistor SMD 0402")
		(property "Reference" "R220"
			(at 3.599 0.358 180)
			(layer "B.SilkS")
			(effects
				(font
					(size 0.7 0.7)
					(thickness 0.15)
				)
				(justify left bottom mirror)
			)
		)
		(property "Value" "R_10k_0402"
			(at 0 -1.4 180)
			(layer "B.Fab")
			(effects
				(font
					(size 0.7 0.7)
					(thickness 0.15)
				)
				(justify left bottom mirror)
			)
		)
		(property "Description" "SMD Chip Resistor, 10 kohm, ± 1%, 62.5 mW, 0402 [1005 Metric], Thick Film, General Purpose"
			(at 0 0 0)
			(layer "F.Fab")
			(hide yes)
			(effects
				(font
					(size 1.27 1.27)
					(thickness 0.15)
				)
			)
		)
		(property "Author" "Antmicro"
			(at 0 0 0)
			(layer "B.Fab")
			(hide yes)
			(effects
				(font
					(size 1 1)
					(thickness 0.15)
				)
				(justify mirror)
			)
		)
		(property "License" "Apache-2.0"
			(at 0 0 0)
			(layer "B.Fab")
			(hide yes)
			(effects
				(font
					(size 1 1)
					(thickness 0.15)
				)
				(justify mirror)
			)
		)
		(property "MPN" "CR0402-FX-1002GLF"
			(at 0 0 0)
			(layer "B.Fab")
			(hide yes)
			(effects
				(font
					(size 1 1)
					(thickness 0.15)
				)
				(justify mirror)
			)
		)
		(property "Manufacturer" "Bourns"
			(at 0 0 0)
			(layer "B.Fab")
			(hide yes)
			(effects
				(font
					(size 1 1)
					(thickness 0.15)
				)
				(justify mirror)
			)
		)
		(property "Tolerance" "1%"
			(at 0 0 0)
			(layer "B.Fab")
			(hide yes)
			(effects
				(font
					(size 1 1)
					(thickness 0.15)
				)
				(justify mirror)
			)
		)
		(property "Val" "10k"
			(at 0 0 0)
			(layer "B.Fab")
			(hide yes)
			(effects
				(font
					(size 1 1)
					(thickness 0.15)
				)
				(justify mirror)
			)
		)
		(sheetname "HDMI + Ethernet")
		(sheetfile "hdmi-ethernet.kicad_sch")
		(attr smd)
		(fp_rect
			(start -0.925 0.47)
			(end 0.925 -0.47)
			(stroke
				(width 0.05)
				(type default)
			)
			(fill no)
			(layer "B.CrtYd")
		)
		(fp_rect
			(start -0.5 0.25)
			(end 0.5 -0.25)
			(stroke
				(width 0.15)
				(type solid)
			)
			(fill no)
			(layer "B.Fab")
		)
		(pad "1" smd roundrect
			(at -0.48 0)
			(size 0.59 0.64)
			(layers "B.Cu" "B.Mask" "B.Paste")
			(roundrect_rratio 0.25)
			(net 945 "/HDMI + Ethernet/ETH_PHY_RXD1")
			(pintype "passive")
		)
		(pad "2" smd roundrect
			(at 0.48 0)
			(size 0.59 0.64)
			(layers "B.Cu" "B.Mask" "B.Paste")
			(roundrect_rratio 0.25)
			(net 26 "+1V8")
			(pintype "passive")
		)
	)
	(footprint "antmicro-footprints:R_0402_1005Metric"
		(layer "B.Cu")
		(at 185.500001 79.800001 90)
		(descr "Resistor SMD 0402")
		(tags "resistor SMD 0402")
		(property "Reference" "R142"
			(at -0.725 0.4 270)
			(layer "B.SilkS")
			(effects
				(font
					(size 0.7 0.7)
					(thickness 0.15)
				)
				(justify left bottom mirror)
			)
		)
		(property "Value" "R_100R_0402"
			(at 0 -1.4 270)
			(layer "B.Fab")
			(effects
				(font
					(size 0.7 0.7)
					(thickness 0.15)
				)
				(justify left bottom mirror)
			)
		)
		(property "Description" "SMD Chip Resistor, 100 ohm, ± 1%, 62.5 mW, 0402 [1005 Metric], Thick Film, General Purpose"
			(at 0 0 90)
			(layer "F.Fab")
			(hide yes)
			(effects
				(font
					(size 1.27 1.27)
					(thickness 0.15)
				)
			)
		)
		(property "Author" "Antmicro"
			(at 265.300002 -105.7 0)
			(layer "B.Fab")
			(hide yes)
			(effects
				(font
					(size 1 1)
					(thickness 0.15)
				)
				(justify mirror)
			)
		)
		(property "License" "Apache-2.0"
			(at 265.300002 -105.7 0)
			(layer "B.Fab")
			(hide yes)
			(effects
				(font
					(size 1 1)
					(thickness 0.15)
				)
				(justify mirror)
			)
		)
		(property "MPN" "CR0402-FX-1000GLF"
			(at 265.300002 -105.7 0)
			(layer "B.Fab")
			(hide yes)
			(effects
				(font
					(size 1 1)
					(thickness 0.15)
				)
				(justify mirror)
			)
		)
		(property "Manufacturer" "Bourns"
			(at 265.300002 -105.7 0)
			(layer "B.Fab")
			(hide yes)
			(effects
				(font
					(size 1 1)
					(thickness 0.15)
				)
				(justify mirror)
			)
		)
		(property "Tolerance" "1%"
			(at 265.300002 -105.7 0)
			(layer "B.Fab")
			(hide yes)
			(effects
				(font
					(size 1 1)
					(thickness 0.15)
				)
				(justify mirror)
			)
		)
		(property "Val" "100R"
			(at 265.300002 -105.7 0)
			(layer "B.Fab")
			(hide yes)
			(effects
				(font
					(size 1 1)
					(thickness 0.15)
				)
				(justify mirror)
			)
		)
		(sheetname "User GPIO + LED + button + DIP switch")
		(sheetfile "user-gpio.kicad_sch")
		(attr smd)
		(fp_rect
			(start -0.925 0.47)
			(end 0.925 -0.47)
			(stroke
				(width 0.05)
				(type default)
			)
			(fill no)
			(layer "B.CrtYd")
		)
		(fp_rect
			(start -0.5 0.25)
			(end 0.5 -0.25)
			(stroke
				(width 0.15)
				(type solid)
			)
			(fill no)
			(layer "B.Fab")
		)
		(pad "1" smd roundrect
			(at -0.48 0 90)
			(size 0.59 0.64)
			(layers "B.Cu" "B.Mask" "B.Paste")
			(roundrect_rratio 0.25)
			(net 487 "/FPGA Bank 12 & 13/CW_HEADER.HS1")
			(pintype "passive")
		)
		(pad "2" smd roundrect
			(at 0.48 0 90)
			(size 0.59 0.64)
			(layers "B.Cu" "B.Mask" "B.Paste")
			(roundrect_rratio 0.25)
			(net 822 "/User GPIO + LED + button + DIP switch/CW_20PIN_HS1")
			(pintype "passive")
		)
	)
	(footprint "antmicro-footprints:R_0402_1005Metric"
		(layer "B.Cu")
		(at 207.1 128.6)
		(descr "Resistor SMD 0402")
		(tags "resistor SMD 0402")
		(property "Reference" "R338"
			(at 3.675 0.375 180)
			(layer "B.SilkS")
			(effects
				(font
					(size 0.7 0.7)
					(thickness 0.15)
				)
				(justify left bottom mirror)
			)
		)
		(property "Value" "R_1k_0402"
			(at 0 -1.4 180)
			(layer "B.Fab")
			(effects
				(font
					(size 0.7 0.7)
					(thickness 0.15)
				)
				(justify left bottom mirror)
			)
		)
		(property "Description" "SMD Chip Resistor, 1 kohm, ± 1%, 63 mW, 0402 [1005 Metric], Thick Film, General Purpose"
			(at 0 0 0)
			(layer "F.Fab")
			(hide yes)
			(effects
				(font
					(size 1.27 1.27)
					(thickness 0.15)
				)
			)
		)
		(property "Author" "Antmicro"
			(at 0 0 0)
			(layer "B.Fab")
			(hide yes)
			(effects
				(font
					(size 1 1)
					(thickness 0.15)
				)
				(justify mirror)
			)
		)
		(property "License" "Apache-2.0"
			(at 0 0 0)
			(layer "B.Fab")
			(hide yes)
			(effects
				(font
					(size 1 1)
					(thickness 0.15)
				)
				(justify mirror)
			)
		)
		(property "MPN" "CR0402-FX-1001GLF"
			(at 0 0 0)
			(layer "B.Fab")
			(hide yes)
			(effects
				(font
					(size 1 1)
					(thickness 0.15)
				)
				(justify mirror)
			)
		)
		(property "Manufacturer" "Bourns"
			(at 0 0 0)
			(layer "B.Fab")
			(hide yes)
			(effects
				(font
					(size 1 1)
					(thickness 0.15)
				)
				(justify mirror)
			)
		)
		(property "Tolerance" "1%"
			(at 0 0 0)
			(layer "B.Fab")
			(hide yes)
			(effects
				(font
					(size 1 1)
					(thickness 0.15)
				)
				(justify mirror)
			)
		)
		(property "Val" "1k"
			(at 0 0 0)
			(layer "B.Fab")
			(hide yes)
			(effects
				(font
					(size 1 1)
					(thickness 0.15)
				)
				(justify mirror)
			)
		)
		(sheetname "FPGA Bank 14 & 15")
		(sheetfile "fpga-bank-14-15.kicad_sch")
		(attr smd)
		(fp_rect
			(start -0.925 0.47)
			(end 0.925 -0.47)
			(stroke
				(width 0.05)
				(type default)
			)
			(fill no)
			(layer "B.CrtYd")
		)
		(fp_rect
			(start -0.5 0.25)
			(end 0.5 -0.25)
			(stroke
				(width 0.15)
				(type solid)
			)
			(fill no)
			(layer "B.Fab")
		)
		(pad "1" smd roundrect
			(at -0.48 0)
			(size 0.59 0.64)
			(layers "B.Cu" "B.Mask" "B.Paste")
			(roundrect_rratio 0.25)
			(net 1 "GND")
			(pintype "passive")
		)
		(pad "2" smd roundrect
			(at 0.48 0)
			(size 0.59 0.64)
			(layers "B.Cu" "B.Mask" "B.Paste")
			(roundrect_rratio 0.25)
			(net 566 "/FPGA Bank 14 & 15/CFG_PUDC")
			(pintype "passive")
		)
	)
)
